(kicad_pcb
	(version 20260206)
	(generator "pcbnew")
	(generator_version "10.0")
	(general
		(thickness 1.6)
		(legacy_teardrops no)
	)
	(paper "A4")
	(title_block
		(title "04192023_DAF0TMB3IC0_F0TG_MB_C_brd_V02_OCP.brd")
		(comment 1 "Grand Teton / footprints 5090-5097 of 8354")
	)
	(layers
		(0 "F.Cu" signal "TOP")
		(4 "In1.Cu" signal "GND")
		(6 "In2.Cu" signal "IN1")
		(8 "In3.Cu" signal "GND1")
		(10 "In4.Cu" signal "IN2")
		(12 "In5.Cu" signal "GND2")
		(14 "In6.Cu" signal "IN3")
		(16 "In7.Cu" signal "GND3")
		(18 "In8.Cu" signal "VCC")
		(20 "In9.Cu" signal "VCC1")
		(22 "In10.Cu" signal "GND4")
		(24 "In11.Cu" signal "IN4")
		(26 "In12.Cu" signal "GND5")
		(28 "In13.Cu" signal "IN5")
		(30 "In14.Cu" signal "GND6")
		(32 "In15.Cu" signal "IN6")
		(34 "In16.Cu" signal "GND7")
		(2 "B.Cu" signal "BOTTOM")
		(9 "F.Adhes" user "F.Adhesive")
		(11 "B.Adhes" user "B.Adhesive")
		(13 "F.Paste" user "Package Geometry/Pastemask Top")
		(15 "B.Paste" user "Package Geometry/Pastemask Bottom")
		(5 "F.SilkS" user "Ref Des/Silkscreen Top")
		(7 "B.SilkS" user "Ref Des/Silkscreen Bottom")
		(1 "F.Mask" user "Board Geometry/Soldermask Top")
		(3 "B.Mask" user "Board Geometry/Soldermask Bottom")
		(17 "Dwgs.User" user "User.Drawings")
		(19 "Cmts.User" user "User.Comments")
		(21 "Eco1.User" user "User.Eco1")
		(23 "Eco2.User" user "User.Eco2")
		(25 "Edge.Cuts" user "Board Geometry/Outline")
		(27 "Margin" user)
		(31 "F.CrtYd" user "Package Geometry/Place Bound Top")
		(29 "B.CrtYd" user "Package Geometry/Place Bound Bottom")
		(35 "F.Fab" user "Ref Des/Assembly Top")
		(33 "B.Fab" user "Ref Des/Assembly Bottom")
	)
	(footprint ""
		(layer "B.Cu")
		(at 230.6828 -338.582 180)
		(property "Reference" "R6757"
			(at 0 0 0)
			(layer "B.SilkS")
			(hide yes)
			(effects
				(font
					(size 1.27 1.27)
				)
				(justify mirror)
			)
		)
		(property "Value" ""
			(at 0 0 0)
			(layer "B.Fab")
			(effects
				(font
					(size 1.27 1.27)
				)
				(justify mirror)
			)
		)
		(duplicate_pad_numbers_are_jumpers no)
		(fp_line
			(start 0.32512 0.175006)
			(end 0.32512 -0.175006)
			(stroke
				(width 0.1)
				(type default)
			)
			(layer "B.Fab")
		)
		(fp_line
			(start 0.32512 -0.175006)
			(end -0.32512 -0.175006)
			(stroke
				(width 0.1)
				(type default)
			)
			(layer "B.Fab")
		)
		(fp_line
			(start -0.32512 0.175006)
			(end 0.32512 0.175006)
			(stroke
				(width 0.1)
				(type default)
			)
			(layer "B.Fab")
		)
		(fp_line
			(start -0.32512 -0.175006)
			(end -0.32512 0.175006)
			(stroke
				(width 0.1)
				(type default)
			)
			(layer "B.Fab")
		)
		(pad "1" smd rect
			(at 0.2667 0)
			(size 0.3048 0.381)
			(layers "B.Cu" "B.Mask" "B.Paste")
			(net "SMB_RT_CPU0_P1_SCL")
		)
		(pad "2" smd rect
			(at -0.2667 0 180)
			(size 0.3048 0.381)
			(layers "B.Cu" "B.Mask" "B.Paste")
			(net "SMB_RT_CPU0_P1_R_SCL")
		)
	)
	(footprint ""
		(layer "B.Cu")
		(at 301.48657 -346.784168 90)
		(property "Reference" "PC152_1"
			(at 0 0 90)
			(layer "B.SilkS")
			(hide yes)
			(effects
				(font
					(size 1.27 1.27)
				)
				(justify mirror)
			)
		)
		(property "Value" ""
			(at 0 0 90)
			(layer "B.Fab")
			(effects
				(font
					(size 1.27 1.27)
				)
				(justify mirror)
			)
		)
		(duplicate_pad_numbers_are_jumpers no)
		(fp_line
			(start 1.524 -0.762)
			(end -1.524 -0.762)
			(stroke
				(width 0.1524)
				(type default)
			)
			(layer "B.SilkS")
		)
		(fp_line
			(start -1.524 -0.762)
			(end -1.524 0.762)
			(stroke
				(width 0.1524)
				(type default)
			)
			(layer "B.SilkS")
		)
		(fp_line
			(start 1.524 0.762)
			(end 1.524 -0.762)
			(stroke
				(width 0.1524)
				(type default)
			)
			(layer "B.SilkS")
		)
		(fp_line
			(start -1.524 0.762)
			(end 1.524 0.762)
			(stroke
				(width 0.1524)
				(type default)
			)
			(layer "B.SilkS")
		)
		(fp_line
			(start 1.1049 -0.724916)
			(end 1.1049 0.724916)
			(stroke
				(width 0.1)
				(type default)
			)
			(layer "B.Fab")
		)
		(fp_line
			(start -1.1049 -0.724916)
			(end 1.1049 -0.724916)
			(stroke
				(width 0.1)
				(type default)
			)
			(layer "B.Fab")
		)
		(fp_line
			(start 1.1049 0.724916)
			(end -1.1049 0.724916)
			(stroke
				(width 0.1)
				(type default)
			)
			(layer "B.Fab")
		)
		(fp_line
			(start -1.1049 0.724916)
			(end -1.1049 -0.724916)
			(stroke
				(width 0.1)
				(type default)
			)
			(layer "B.Fab")
		)
		(pad "1" smd rect
			(at 0.889 0 90)
			(size 1.016 1.27)
			(layers "B.Cu" "B.Mask" "B.Paste")
			(net "SW_P12V_AUX_PVDDIO_P0_FLT")
		)
		(pad "2" smd rect
			(at -0.889 0 90)
			(size 1.016 1.27)
			(layers "B.Cu" "B.Mask" "B.Paste")
			(net "GND")
		)
	)
	(footprint ""
		(layer "B.Cu")
		(at 338.859876 -66.708782 90)
		(property "Reference" "R3094"
			(at 0 0 90)
			(layer "B.SilkS")
			(hide yes)
			(effects
				(font
					(size 1.27 1.27)
				)
				(justify mirror)
			)
		)
		(property "Value" ""
			(at 0 0 90)
			(layer "B.Fab")
			(effects
				(font
					(size 1.27 1.27)
				)
				(justify mirror)
			)
		)
		(duplicate_pad_numbers_are_jumpers no)
		(fp_line
			(start 0.7874 -0.4064)
			(end -0.7874 -0.4064)
			(stroke
				(width 0.1524)
				(type default)
			)
			(layer "B.SilkS")
		)
		(fp_line
			(start -0.7874 -0.4064)
			(end -0.7874 0.4064)
			(stroke
				(width 0.1524)
				(type default)
			)
			(layer "B.SilkS")
		)
		(fp_line
			(start 0.7874 0.4064)
			(end 0.7874 -0.4064)
			(stroke
				(width 0.1524)
				(type default)
			)
			(layer "B.SilkS")
		)
		(fp_line
			(start -0.7874 0.4064)
			(end 0.7874 0.4064)
			(stroke
				(width 0.1524)
				(type default)
			)
			(layer "B.SilkS")
		)
		(fp_line
			(start 0.67945 -0.305054)
			(end 0.12065 -0.305054)
			(stroke
				(width 0.1)
				(type default)
			)
			(layer "B.Fab")
		)
		(fp_line
			(start 0.12065 -0.305054)
			(end 0.12065 -0.2794)
			(stroke
				(width 0.1)
				(type default)
			)
			(layer "B.Fab")
		)
		(fp_line
			(start -0.12065 -0.3048)
			(end -0.67945 -0.3048)
			(stroke
				(width 0.1)
				(type default)
			)
			(layer "B.Fab")
		)
		(fp_line
			(start -0.67945 -0.3048)
			(end -0.67945 0.3048)
			(stroke
				(width 0.1)
				(type default)
			)
			(layer "B.Fab")
		)
		(fp_line
			(start 0.12065 -0.2794)
			(end -0.12065 -0.2794)
			(stroke
				(width 0.1)
				(type default)
			)
			(layer "B.Fab")
		)
		(fp_line
			(start -0.12065 -0.2794)
			(end -0.12065 -0.3048)
			(stroke
				(width 0.1)
				(type default)
			)
			(layer "B.Fab")
		)
		(fp_line
			(start 0.12065 0.2794)
			(end 0.12065 0.3048)
			(stroke
				(width 0.1)
				(type default)
			)
			(layer "B.Fab")
		)
		(fp_line
			(start -0.120396 0.2794)
			(end 0.12065 0.2794)
			(stroke
				(width 0.1)
				(type default)
			)
			(layer "B.Fab")
		)
		(fp_line
			(start 0.67945 0.3048)
			(end 0.67945 -0.305054)
			(stroke
				(width 0.1)
				(type default)
			)
			(layer "B.Fab")
		)
		(fp_line
			(start 0.12065 0.3048)
			(end 0.67945 0.3048)
			(stroke
				(width 0.1)
				(type default)
			)
			(layer "B.Fab")
		)
		(fp_line
			(start -0.120396 0.3048)
			(end -0.120396 0.2794)
			(stroke
				(width 0.1)
				(type default)
			)
			(layer "B.Fab")
		)
		(fp_line
			(start -0.67945 0.3048)
			(end -0.120396 0.3048)
			(stroke
				(width 0.1)
				(type default)
			)
			(layer "B.Fab")
		)
		(pad "1" smd circle
			(at 0.40005 0 270)
			(size 0 0)
			(layers "B.Cu" "B.Mask" "B.Paste")
			(net "LED_PWRGD_PVDDCR_SOC_P1_R")
		)
		(pad "2" smd circle
			(at -0.40005 0 270)
			(size 0 0)
			(layers "B.Cu" "B.Mask" "B.Paste")
			(net "P3V3_AUX")
		)
	)
	(footprint ""
		(layer "B.Cu")
		(at 359.833926 -416.923474 180)
		(property "Reference" "C1774"
			(at 0 0 0)
			(layer "B.SilkS")
			(hide yes)
			(effects
				(font
					(size 1.27 1.27)
				)
				(justify mirror)
			)
		)
		(property "Value" ""
			(at 0 0 0)
			(layer "B.Fab")
			(effects
				(font
					(size 1.27 1.27)
				)
				(justify mirror)
			)
		)
		(duplicate_pad_numbers_are_jumpers no)
		(fp_line
			(start 0.7874 0.4064)
			(end 0.7874 -0.4064)
			(stroke
				(width 0.1524)
				(type default)
			)
			(layer "B.SilkS")
		)
		(fp_line
			(start 0.7874 -0.4064)
			(end -0.7874 -0.4064)
			(stroke
				(width 0.1524)
				(type default)
			)
			(layer "B.SilkS")
		)
		(fp_line
			(start -0.7874 0.4064)
			(end 0.7874 0.4064)
			(stroke
				(width 0.1524)
				(type default)
			)
			(layer "B.SilkS")
		)
		(fp_line
			(start -0.7874 -0.4064)
			(end -0.7874 0.4064)
			(stroke
				(width 0.1524)
				(type default)
			)
			(layer "B.SilkS")
		)
		(fp_line
			(start 0.67945 0.3048)
			(end 0.67945 -0.305054)
			(stroke
				(width 0.1)
				(type default)
			)
			(layer "B.Fab")
		)
		(fp_line
			(start 0.67945 -0.305054)
			(end 0.12065 -0.305054)
			(stroke
				(width 0.1)
				(type default)
			)
			(layer "B.Fab")
		)
		(fp_line
			(start 0.12065 0.3048)
			(end 0.67945 0.3048)
			(stroke
				(width 0.1)
				(type default)
			)
			(layer "B.Fab")
		)
		(fp_line
			(start 0.12065 0.2794)
			(end 0.12065 0.3048)
			(stroke
				(width 0.1)
				(type default)
			)
			(layer "B.Fab")
		)
		(fp_line
			(start 0.12065 -0.2794)
			(end -0.12065 -0.2794)
			(stroke
				(width 0.1)
				(type default)
			)
			(layer "B.Fab")
		)
		(fp_line
			(start 0.12065 -0.305054)
			(end 0.12065 -0.2794)
			(stroke
				(width 0.1)
				(type default)
			)
			(layer "B.Fab")
		)
		(fp_line
			(start -0.120396 0.3048)
			(end -0.120396 0.2794)
			(stroke
				(width 0.1)
				(type default)
			)
			(layer "B.Fab")
		)
		(fp_line
			(start -0.120396 0.2794)
			(end 0.12065 0.2794)
			(stroke
				(width 0.1)
				(type default)
			)
			(layer "B.Fab")
		)
		(fp_line
			(start -0.12065 -0.2794)
			(end -0.12065 -0.3048)
			(stroke
				(width 0.1)
				(type default)
			)
			(layer "B.Fab")
		)
		(fp_line
			(start -0.12065 -0.3048)
			(end -0.67945 -0.3048)
			(stroke
				(width 0.1)
				(type default)
			)
			(layer "B.Fab")
		)
		(fp_line
			(start -0.67945 0.3048)
			(end -0.120396 0.3048)
			(stroke
				(width 0.1)
				(type default)
			)
			(layer "B.Fab")
		)
		(fp_line
			(start -0.67945 -0.3048)
			(end -0.67945 0.3048)
			(stroke
				(width 0.1)
				(type default)
			)
			(layer "B.Fab")
		)
		(pad "1" smd circle
			(at 0.40005 0)
			(size 0 0)
			(layers "B.Cu" "B.Mask" "B.Paste")
			(net "FM_SWB_PWRGD_ISO")
		)
		(pad "2" smd circle
			(at -0.40005 0)
			(size 0 0)
			(layers "B.Cu" "B.Mask" "B.Paste")
			(net "GND")
		)
	)
	(footprint ""
		(layer "B.Cu")
		(at 362.265976 -256.012188 -90)
		(property "Reference" "C2543"
			(at 0 0 90)
			(layer "B.SilkS")
			(hide yes)
			(effects
				(font
					(size 1.27 1.27)
				)
				(justify mirror)
			)
		)
		(property "Value" ""
			(at 0 0 90)
			(layer "B.Fab")
			(effects
				(font
					(size 1.27 1.27)
				)
				(justify mirror)
			)
		)
		(duplicate_pad_numbers_are_jumpers no)
		(fp_line
			(start -0.7874 0.4064)
			(end 0.7874 0.4064)
			(stroke
				(width 0.1524)
				(type default)
			)
			(layer "B.SilkS")
		)
		(fp_line
			(start 0.7874 0.4064)
			(end 0.7874 -0.4064)
			(stroke
				(width 0.1524)
				(type default)
			)
			(layer "B.SilkS")
		)
		(fp_line
			(start -0.7874 -0.4064)
			(end -0.7874 0.4064)
			(stroke
				(width 0.1524)
				(type default)
			)
			(layer "B.SilkS")
		)
		(fp_line
			(start 0.7874 -0.4064)
			(end -0.7874 -0.4064)
			(stroke
				(width 0.1524)
				(type default)
			)
			(layer "B.SilkS")
		)
		(fp_line
			(start -0.67945 0.3048)
			(end -0.120396 0.3048)
			(stroke
				(width 0.1)
				(type default)
			)
			(layer "B.Fab")
		)
		(fp_line
			(start -0.120396 0.3048)
			(end -0.120396 0.2794)
			(stroke
				(width 0.1)
				(type default)
			)
			(layer "B.Fab")
		)
		(fp_line
			(start 0.12065 0.3048)
			(end 0.67945 0.3048)
			(stroke
				(width 0.1)
				(type default)
			)
			(layer "B.Fab")
		)
		(fp_line
			(start 0.67945 0.3048)
			(end 0.67945 -0.305054)
			(stroke
				(width 0.1)
				(type default)
			)
			(layer "B.Fab")
		)
		(fp_line
			(start -0.120396 0.2794)
			(end 0.12065 0.2794)
			(stroke
				(width 0.1)
				(type default)
			)
			(layer "B.Fab")
		)
		(fp_line
			(start 0.12065 0.2794)
			(end 0.12065 0.3048)
			(stroke
				(width 0.1)
				(type default)
			)
			(layer "B.Fab")
		)
		(fp_line
			(start -0.12065 -0.2794)
			(end -0.12065 -0.3048)
			(stroke
				(width 0.1)
				(type default)
			)
			(layer "B.Fab")
		)
		(fp_line
			(start 0.12065 -0.2794)
			(end -0.12065 -0.2794)
			(stroke
				(width 0.1)
				(type default)
			)
			(layer "B.Fab")
		)
		(fp_line
			(start -0.67945 -0.3048)
			(end -0.67945 0.3048)
			(stroke
				(width 0.1)
				(type default)
			)
			(layer "B.Fab")
		)
		(fp_line
			(start -0.12065 -0.3048)
			(end -0.67945 -0.3048)
			(stroke
				(width 0.1)
				(type default)
			)
			(layer "B.Fab")
		)
		(fp_line
			(start 0.12065 -0.305054)
			(end 0.12065 -0.2794)
			(stroke
				(width 0.1)
				(type default)
			)
			(layer "B.Fab")
		)
		(fp_line
			(start 0.67945 -0.305054)
			(end 0.12065 -0.305054)
			(stroke
				(width 0.1)
				(type default)
			)
			(layer "B.Fab")
		)
		(pad "1" smd circle
			(at 0.40005 0 90)
			(size 0 0)
			(layers "B.Cu" "B.Mask" "B.Paste")
			(net "PVDDCR_SOC_P0")
		)
		(pad "2" smd circle
			(at -0.40005 0 90)
			(size 0 0)
			(layers "B.Cu" "B.Mask" "B.Paste")
			(net "GND")
		)
	)
	(footprint ""
		(layer "B.Cu")
		(at 422.2115 -395.148562 90)
		(property "Reference" "C979"
			(at 0 0 90)
			(layer "B.SilkS")
			(hide yes)
			(effects
				(font
					(size 1.27 1.27)
				)
				(justify mirror)
			)
		)
		(property "Value" ""
			(at 0 0 90)
			(layer "B.Fab")
			(effects
				(font
					(size 1.27 1.27)
				)
				(justify mirror)
			)
		)
		(duplicate_pad_numbers_are_jumpers no)
		(fp_line
			(start 0.299974 -0.150114)
			(end -0.299974 -0.150114)
			(stroke
				(width 0.1)
				(type default)
			)
			(layer "B.Fab")
		)
		(fp_line
			(start -0.299974 -0.150114)
			(end -0.299974 0.150114)
			(stroke
				(width 0.1)
				(type default)
			)
			(layer "B.Fab")
		)
		(fp_line
			(start 0.299974 0.150114)
			(end 0.299974 -0.150114)
			(stroke
				(width 0.1)
				(type default)
			)
			(layer "B.Fab")
		)
		(fp_line
			(start -0.299974 0.150114)
			(end 0.299974 0.150114)
			(stroke
				(width 0.1)
				(type default)
			)
			(layer "B.Fab")
		)
		(pad "1" smd rect
			(at 0.2667 0 270)
			(size 0.3048 0.381)
			(layers "B.Cu" "B.Mask" "B.Paste")
			(net "P0V9_CPU0_RT2_2A")
		)
		(pad "2" smd rect
			(at -0.2667 0 270)
			(size 0.3048 0.381)
			(layers "B.Cu" "B.Mask" "B.Paste")
			(net "GND")
		)
	)
	(footprint ""
		(layer "B.Cu")
		(at 347.008958 -252.54331 180)
		(property "Reference" "C2516"
			(at 0 0 0)
			(layer "B.SilkS")
			(hide yes)
			(effects
				(font
					(size 1.27 1.27)
				)
				(justify mirror)
			)
		)
		(property "Value" ""
			(at 0 0 0)
			(layer "B.Fab")
			(effects
				(font
					(size 1.27 1.27)
				)
				(justify mirror)
			)
		)
		(duplicate_pad_numbers_are_jumpers no)
		(fp_line
			(start 0.7874 0.4064)
			(end 0.7874 -0.4064)
			(stroke
				(width 0.1524)
				(type default)
			)
			(layer "B.SilkS")
		)
		(fp_line
			(start 0.7874 -0.4064)
			(end -0.7874 -0.4064)
			(stroke
				(width 0.1524)
				(type default)
			)
			(layer "B.SilkS")
		)
		(fp_line
			(start -0.7874 0.4064)
			(end 0.7874 0.4064)
			(stroke
				(width 0.1524)
				(type default)
			)
			(layer "B.SilkS")
		)
		(fp_line
			(start -0.7874 -0.4064)
			(end -0.7874 0.4064)
			(stroke
				(width 0.1524)
				(type default)
			)
			(layer "B.SilkS")
		)
		(fp_line
			(start 0.67945 0.3048)
			(end 0.67945 -0.305054)
			(stroke
				(width 0.1)
				(type default)
			)
			(layer "B.Fab")
		)
		(fp_line
			(start 0.67945 -0.305054)
			(end 0.12065 -0.305054)
			(stroke
				(width 0.1)
				(type default)
			)
			(layer "B.Fab")
		)
		(fp_line
			(start 0.12065 0.3048)
			(end 0.67945 0.3048)
			(stroke
				(width 0.1)
				(type default)
			)
			(layer "B.Fab")
		)
		(fp_line
			(start 0.12065 0.2794)
			(end 0.12065 0.3048)
			(stroke
				(width 0.1)
				(type default)
			)
			(layer "B.Fab")
		)
		(fp_line
			(start 0.12065 -0.2794)
			(end -0.12065 -0.2794)
			(stroke
				(width 0.1)
				(type default)
			)
			(layer "B.Fab")
		)
		(fp_line
			(start 0.12065 -0.305054)
			(end 0.12065 -0.2794)
			(stroke
				(width 0.1)
				(type default)
			)
			(layer "B.Fab")
		)
		(fp_line
			(start -0.120396 0.3048)
			(end -0.120396 0.2794)
			(stroke
				(width 0.1)
				(type default)
			)
			(layer "B.Fab")
		)
		(fp_line
			(start -0.120396 0.2794)
			(end 0.12065 0.2794)
			(stroke
				(width 0.1)
				(type default)
			)
			(layer "B.Fab")
		)
		(fp_line
			(start -0.12065 -0.2794)
			(end -0.12065 -0.3048)
			(stroke
				(width 0.1)
				(type default)
			)
			(layer "B.Fab")
		)
		(fp_line
			(start -0.12065 -0.3048)
			(end -0.67945 -0.3048)
			(stroke
				(width 0.1)
				(type default)
			)
			(layer "B.Fab")
		)
		(fp_line
			(start -0.67945 0.3048)
			(end -0.120396 0.3048)
			(stroke
				(width 0.1)
				(type default)
			)
			(layer "B.Fab")
		)
		(fp_line
			(start -0.67945 -0.3048)
			(end -0.67945 0.3048)
			(stroke
				(width 0.1)
				(type default)
			)
			(layer "B.Fab")
		)
		(pad "1" smd circle
			(at 0.40005 0)
			(size 0 0)
			(layers "B.Cu" "B.Mask" "B.Paste")
			(net "PVDD18_S5_P0")
		)
		(pad "2" smd circle
			(at -0.40005 0)
			(size 0 0)
			(layers "B.Cu" "B.Mask" "B.Paste")
			(net "GND")
		)
	)
	(footprint ""
		(layer "B.Cu")
		(at 182.332376 -116.242846 180)
		(property "Reference" "C1172"
			(at 0 0 0)
			(layer "B.SilkS")
			(hide yes)
			(effects
				(font
					(size 1.27 1.27)
				)
				(justify mirror)
			)
		)
		(property "Value" ""
			(at 0 0 0)
			(layer "B.Fab")
			(effects
				(font
					(size 1.27 1.27)
				)
				(justify mirror)
			)
		)
		(duplicate_pad_numbers_are_jumpers no)
		(fp_line
			(start 0.69215 0.2921)
			(end 0.69215 -0.2921)
			(stroke
				(width 0.1524)
				(type default)
			)
			(layer "B.SilkS")
		)
		(fp_line
			(start 0.69215 -0.2921)
			(end -0.69215 -0.2921)
			(stroke
				(width 0.1524)
				(type default)
			)
			(layer "B.SilkS")
		)
		(fp_line
			(start -0.69215 0.2921)
			(end 0.69215 0.2921)
			(stroke
				(width 0.1524)
				(type default)
			)
			(layer "B.SilkS")
		)
		(fp_line
			(start -0.69215 -0.2921)
			(end -0.69215 0.2921)
			(stroke
				(width 0.1524)
				(type default)
			)
			(layer "B.SilkS")
		)
		(fp_line
			(start 0.51435 0.2794)
			(end 0.51435 -0.2794)
			(stroke
				(width 0.1)
				(type default)
			)
			(layer "B.Fab")
		)
		(fp_line
			(start 0.51435 -0.2794)
			(end -0.51435 -0.2794)
			(stroke
				(width 0.1)
				(type default)
			)
			(layer "B.Fab")
		)
		(fp_line
			(start -0.51435 0.2794)
			(end 0.51435 0.2794)
			(stroke
				(width 0.1)
				(type default)
			)
			(layer "B.Fab")
		)
		(fp_line
			(start -0.51435 -0.2794)
			(end -0.51435 0.2794)
			(stroke
				(width 0.1)
				(type default)
			)
			(layer "B.Fab")
		)
		(pad "1" smd circle
			(at 0.40005 0)
			(size 0 0)
			(layers "B.Cu" "B.Mask" "B.Paste")
			(net "P3V3_AUX")
		)
		(pad "2" smd circle
			(at -0.40005 0)
			(size 0 0)
			(layers "B.Cu" "B.Mask" "B.Paste")
			(net "GND")
		)
		(zone
			(layer "B.Cu")
			(hatch none 0.5)
			(connect_pads
				(clearance 0)
			)
			(min_thickness 0.25)
			(keepout
				(tracks not_allowed)
				(vias allowed)
				(pads allowed)
				(copperpour not_allowed)
				(footprints allowed)
			)
			(placement
				(enabled no)
				(sheetname "")
			)
			(fill
				(thermal_gap 0.5)
				(thermal_bridge_width 0.5)
				(island_removal_mode 0)
			)
			(polygon
				(pts
					(xy 182.141876 -116.154962) (xy 182.141876 -116.330476) (xy 182.233316 -116.388642) (xy 182.432706 -116.388642)
					(xy 182.522876 -116.330476) (xy 182.522876 -116.155216) (xy 182.432706 -116.096796) (xy 182.233316 -116.096796)
				)
			)
		)
	)
)
